# S9S_MB_2U (Grand Teton) — schematic netlist excerpt (pin names and nets, part order shuffled) for the footprints in the layout excerpt that follows; sources: Cadence DE-HDL packaged netlist, KiCad conversion of 03242023_DA0F0TMBIJ0_F0T_Motherboard_J_brd_V01_OCP.brd

C2382  Q_CAP  100NF 50V 10% EMPTY  pkg C0402  page 307 : A = P12V_AUX_UV_TRIGGER ; B = GND
R4896  Q_RES  0 5% EMPTY  pkg 0402LF  page 305 : A = P12V_HSC_T_CRIT_N ; B = P12V_HSC_T_CRIT_R_N
C961  Q_CAP_DIFFBUS  DIFF BUS_0.22UF 6.3V 20% X6S  pkg C0201  page 173 : \1\ = P5E_CPU0_PE2_TX_C_DP<2> ; \2\ = P5E_CPU0_PE2_TX_DP<2>

(kicad_pcb
	(version 20260206)
	(generator "pcbnew")
	(generator_version "10.0")
	(general
		(thickness 1.6)
		(legacy_teardrops no)
	)
	(paper "A4")
	(title_block
		(title "03242023_DA0F0TMBIJ0_F0T_Motherboard_J_brd_V01_OCP.brd")
		(comment 1 "Grand Teton / footprints 1986-1988 of 6105")
	)
	(layers
		(0 "F.Cu" signal "TOP")
		(4 "In1.Cu" signal "GND")
		(6 "In2.Cu" signal "IN1")
		(8 "In3.Cu" signal "GND1")
		(10 "In4.Cu" signal "IN2")
		(12 "In5.Cu" signal "GND2")
		(14 "In6.Cu" signal "IN3")
		(16 "In7.Cu" signal "GND3")
		(18 "In8.Cu" signal "VCC")
		(20 "In9.Cu" signal "VCC1")
		(22 "In10.Cu" signal "GND4")
		(24 "In11.Cu" signal "IN4")
		(26 "In12.Cu" signal "GND5")
		(28 "In13.Cu" signal "IN5")
		(30 "In14.Cu" signal "GND6")
		(32 "In15.Cu" signal "IN6")
		(34 "In16.Cu" signal "GND7")
		(2 "B.Cu" signal "BOTTOM")
		(9 "F.Adhes" user "F.Adhesive")
		(11 "B.Adhes" user "B.Adhesive")
		(13 "F.Paste" user "Package Geometry/Pastemask Top")
		(15 "B.Paste" user "Package Geometry/Pastemask Bottom")
		(5 "F.SilkS" user "Ref Des/Silkscreen Top")
		(7 "B.SilkS" user "Ref Des/Silkscreen Bottom")
		(1 "F.Mask" user "Board Geometry/Soldermask Top")
		(3 "B.Mask" user "Board Geometry/Soldermask Bottom")
		(17 "Dwgs.User" user "User.Drawings")
		(19 "Cmts.User" user "User.Comments")
		(21 "Eco1.User" user "User.Eco1")
		(23 "Eco2.User" user "User.Eco2")
		(25 "Edge.Cuts" user "Board Geometry/Outline")
		(27 "Margin" user)
		(31 "F.CrtYd" user "Package Geometry/Place Bound Top")
		(29 "B.CrtYd" user "Package Geometry/Place Bound Bottom")
		(35 "F.Fab" user "Ref Des/Assembly Top")
		(33 "B.Fab" user "Ref Des/Assembly Bottom")
	)
	(footprint ""
		(layer "F.Cu")
		(at 288.9377 -406.81402 180)
		(property "Reference" "R4896"
			(at 0 0 180)
			(layer "F.SilkS")
			(hide yes)
			(effects
				(font
					(size 1.27 1.27)
				)
			)
		)
		(property "Value" ""
			(at 0 0 180)
			(layer "F.Fab")
			(effects
				(font
					(size 1.27 1.27)
				)
			)
		)
		(duplicate_pad_numbers_are_jumpers no)
		(fp_line
			(start 0.7874 0.4064)
			(end -0.7874 0.4064)
			(stroke
				(width 0.1524)
				(type default)
			)
			(layer "F.SilkS")
		)
		(fp_line
			(start 0.7874 -0.4064)
			(end 0.7874 0.4064)
			(stroke
				(width 0.1524)
				(type default)
			)
			(layer "F.SilkS")
		)
		(fp_line
			(start -0.7874 0.4064)
			(end -0.7874 -0.4064)
			(stroke
				(width 0.1524)
				(type default)
			)
			(layer "F.SilkS")
		)
		(fp_line
			(start -0.7874 -0.4064)
			(end 0.7874 -0.4064)
			(stroke
				(width 0.1524)
				(type default)
			)
			(layer "F.SilkS")
		)
		(fp_line
			(start 0.67945 0.3048)
			(end 0.120396 0.3048)
			(stroke
				(width 0.1)
				(type default)
			)
			(layer "F.Fab")
		)
		(fp_line
			(start 0.67945 -0.3048)
			(end 0.67945 0.3048)
			(stroke
				(width 0.1)
				(type default)
			)
			(layer "F.Fab")
		)
		(fp_line
			(start 0.12065 -0.2794)
			(end 0.12065 -0.3048)
			(stroke
				(width 0.1)
				(type default)
			)
			(layer "F.Fab")
		)
		(fp_line
			(start 0.12065 -0.3048)
			(end 0.67945 -0.3048)
			(stroke
				(width 0.1)
				(type default)
			)
			(layer "F.Fab")
		)
		(fp_line
			(start 0.120396 0.3048)
			(end 0.120396 0.2794)
			(stroke
				(width 0.1)
				(type default)
			)
			(layer "F.Fab")
		)
		(fp_line
			(start 0.120396 0.2794)
			(end -0.12065 0.2794)
			(stroke
				(width 0.1)
				(type default)
			)
			(layer "F.Fab")
		)
		(fp_line
			(start -0.12065 0.3048)
			(end -0.67945 0.3048)
			(stroke
				(width 0.1)
				(type default)
			)
			(layer "F.Fab")
		)
		(fp_line
			(start -0.12065 0.2794)
			(end -0.12065 0.3048)
			(stroke
				(width 0.1)
				(type default)
			)
			(layer "F.Fab")
		)
		(fp_line
			(start -0.12065 -0.2794)
			(end 0.12065 -0.2794)
			(stroke
				(width 0.1)
				(type default)
			)
			(layer "F.Fab")
		)
		(fp_line
			(start -0.12065 -0.305054)
			(end -0.12065 -0.2794)
			(stroke
				(width 0.1)
				(type default)
			)
			(layer "F.Fab")
		)
		(fp_line
			(start -0.67945 0.3048)
			(end -0.67945 -0.305054)
			(stroke
				(width 0.1)
				(type default)
			)
			(layer "F.Fab")
		)
		(fp_line
			(start -0.67945 -0.305054)
			(end -0.12065 -0.305054)
			(stroke
				(width 0.1)
				(type default)
			)
			(layer "F.Fab")
		)
		(pad "1" smd circle
			(at -0.40005 0 180)
			(size 0 0)
			(layers "F.Cu" "F.Mask" "F.Paste")
			(net "P12V_HSC_T_CRIT_N")
		)
		(pad "2" smd circle
			(at 0.40005 0 180)
			(size 0 0)
			(layers "F.Cu" "F.Mask" "F.Paste")
			(net "P12V_HSC_T_CRIT_R_N")
		)
	)
	(footprint ""
		(layer "F.Cu")
		(at 214.4268 -107.4166 -90)
		(property "Reference" "C2382"
			(at 0 0 270)
			(layer "F.SilkS")
			(hide yes)
			(effects
				(font
					(size 1.27 1.27)
				)
			)
		)
		(property "Value" ""
			(at 0 0 270)
			(layer "F.Fab")
			(effects
				(font
					(size 1.27 1.27)
				)
			)
		)
		(duplicate_pad_numbers_are_jumpers no)
		(fp_line
			(start -0.7874 0.4064)
			(end -0.7874 -0.4064)
			(stroke
				(width 0.1524)
				(type default)
			)
			(layer "F.SilkS")
		)
		(fp_line
			(start 0.7874 0.4064)
			(end -0.7874 0.4064)
			(stroke
				(width 0.1524)
				(type default)
			)
			(layer "F.SilkS")
		)
		(fp_line
			(start -0.7874 -0.4064)
			(end 0.7874 -0.4064)
			(stroke
				(width 0.1524)
				(type default)
			)
			(layer "F.SilkS")
		)
		(fp_line
			(start 0.7874 -0.4064)
			(end 0.7874 0.4064)
			(stroke
				(width 0.1524)
				(type default)
			)
			(layer "F.SilkS")
		)
		(fp_line
			(start -0.67945 0.3048)
			(end -0.67945 -0.305054)
			(stroke
				(width 0.1)
				(type default)
			)
			(layer "F.Fab")
		)
		(fp_line
			(start -0.12065 0.3048)
			(end -0.67945 0.3048)
			(stroke
				(width 0.1)
				(type default)
			)
			(layer "F.Fab")
		)
		(fp_line
			(start 0.120396 0.3048)
			(end 0.120396 0.2794)
			(stroke
				(width 0.1)
				(type default)
			)
			(layer "F.Fab")
		)
		(fp_line
			(start 0.67945 0.3048)
			(end 0.120396 0.3048)
			(stroke
				(width 0.1)
				(type default)
			)
			(layer "F.Fab")
		)
		(fp_line
			(start -0.12065 0.2794)
			(end -0.12065 0.3048)
			(stroke
				(width 0.1)
				(type default)
			)
			(layer "F.Fab")
		)
		(fp_line
			(start 0.120396 0.2794)
			(end -0.12065 0.2794)
			(stroke
				(width 0.1)
				(type default)
			)
			(layer "F.Fab")
		)
		(fp_line
			(start -0.12065 -0.2794)
			(end 0.12065 -0.2794)
			(stroke
				(width 0.1)
				(type default)
			)
			(layer "F.Fab")
		)
		(fp_line
			(start 0.12065 -0.2794)
			(end 0.12065 -0.3048)
			(stroke
				(width 0.1)
				(type default)
			)
			(layer "F.Fab")
		)
		(fp_line
			(start 0.12065 -0.3048)
			(end 0.67945 -0.3048)
			(stroke
				(width 0.1)
				(type default)
			)
			(layer "F.Fab")
		)
		(fp_line
			(start 0.67945 -0.3048)
			(end 0.67945 0.3048)
			(stroke
				(width 0.1)
				(type default)
			)
			(layer "F.Fab")
		)
		(fp_line
			(start -0.67945 -0.305054)
			(end -0.12065 -0.305054)
			(stroke
				(width 0.1)
				(type default)
			)
			(layer "F.Fab")
		)
		(fp_line
			(start -0.12065 -0.305054)
			(end -0.12065 -0.2794)
			(stroke
				(width 0.1)
				(type default)
			)
			(layer "F.Fab")
		)
		(pad "1" smd circle
			(at -0.40005 0 270)
			(size 0 0)
			(layers "F.Cu" "F.Mask" "F.Paste")
			(net "P12V_AUX_UV_TRIGGER")
		)
		(pad "2" smd circle
			(at 0.40005 0 270)
			(size 0 0)
			(layers "F.Cu" "F.Mask" "F.Paste")
			(net "GND")
		)
	)
	(footprint ""
		(layer "F.Cu")
		(at 411.21965 -402.371052 -90)
		(property "Reference" "C961"
			(at 0 0 270)
			(layer "F.SilkS")
			(hide yes)
			(effects
				(font
					(size 1.27 1.27)
				)
			)
		)
		(property "Value" ""
			(at 0 0 270)
			(layer "F.Fab")
			(effects
				(font
					(size 1.27 1.27)
				)
			)
		)
		(duplicate_pad_numbers_are_jumpers no)
		(fp_line
			(start -0.299974 0.150114)
			(end -0.299974 -0.150114)
			(stroke
				(width 0.1)
				(type default)
			)
			(layer "F.Fab")
		)
		(fp_line
			(start 0.299974 0.150114)
			(end -0.299974 0.150114)
			(stroke
				(width 0.1)
				(type default)
			)
			(layer "F.Fab")
		)
		(fp_line
			(start -0.299974 -0.150114)
			(end 0.299974 -0.150114)
			(stroke
				(width 0.1)
				(type default)
			)
			(layer "F.Fab")
		)
		(fp_line
			(start 0.299974 -0.150114)
			(end 0.299974 0.150114)
			(stroke
				(width 0.1)
				(type default)
			)
			(layer "F.Fab")
		)
		(pad "1" smd rect
			(at -0.2667 0 270)
			(size 0.3048 0.381)
			(layers "F.Cu" "F.Mask" "F.Paste")
			(net "P5E_CPU0_PE2_TX_C_DP<2>")
		)
		(pad "2" smd rect
			(at 0.2667 0 270)
			(size 0.3048 0.381)
			(layers "F.Cu" "F.Mask" "F.Paste")
			(net "P5E_CPU0_PE2_TX_DP<2>")
		)
	)
)
